# BASEBOARD_FAB2 (Tioga Pass) — schematic netlist excerpt (pin names and nets, part order shuffled) for the footprints in the layout excerpt that follows; sources: Cadence DE-HDL packaged netlist, KiCad conversion of Wiwynn_Tioga_Pass_MB.brd

R6F2  RES  49.9 1% CHIP  pkg 0402  page 89 : A = FM_ADR_COMPLETE_CPU1_N ; B = FM_ADR_COMPLETE_KLM_N
RT7  1R3F-GP  1%  pkg RCL_GP  page 227 : \1\ = VR_PVDDQ_KLM_PH2_RC ; \2\ = GND
R1D45  RES  0.0 5% CHIP  pkg 0402  page 200 : A = A_HSC_MON ; B = A_HSC_HSN

(kicad_pcb
	(version 20260206)
	(generator "pcbnew")
	(generator_version "10.0")
	(general
		(thickness 1.6)
		(legacy_teardrops no)
	)
	(paper "A4")
	(title_block
		(title "Wiwynn_Tioga_Pass_MB.brd")
		(comment 1 "Tioga Pass / footprints 690-692 of 4770")
	)
	(layers
		(0 "F.Cu" signal "TOP")
		(4 "In1.Cu" signal "L2GND")
		(6 "In2.Cu" signal "L3")
		(8 "In3.Cu" signal "L4GND")
		(10 "In4.Cu" signal "L5")
		(12 "In5.Cu" signal "L6GND")
		(14 "In6.Cu" signal "L7VCC")
		(16 "In7.Cu" signal "L8VCC")
		(18 "In8.Cu" signal "L9GND")
		(20 "In9.Cu" signal "L10")
		(22 "In10.Cu" signal "L11GND")
		(24 "In11.Cu" signal "L12")
		(26 "In12.Cu" signal "L13GND")
		(2 "B.Cu" signal "BOTTOM")
		(9 "F.Adhes" user "F.Adhesive")
		(11 "B.Adhes" user "B.Adhesive")
		(13 "F.Paste" user "Package Geometry/Pastemask Top")
		(15 "B.Paste" user "Package Geometry/Pastemask Bottom")
		(5 "F.SilkS" user "Ref Des/Silkscreen Top")
		(7 "B.SilkS" user "Ref Des/Silkscreen Bottom")
		(1 "F.Mask" user "Board Geometry/Soldermask Top")
		(3 "B.Mask" user "Board Geometry/Soldermask Bottom")
		(17 "Dwgs.User" user "User.Drawings")
		(19 "Cmts.User" user "User.Comments")
		(21 "Eco1.User" user "User.Eco1")
		(23 "Eco2.User" user "User.Eco2")
		(25 "Edge.Cuts" user "Board Geometry/Outline")
		(27 "Margin" user)
		(31 "F.CrtYd" user "Package Geometry/Place Bound Top")
		(29 "B.CrtYd" user "Package Geometry/Place Bound Bottom")
		(35 "F.Fab" user "Ref Des/Assembly Top")
		(33 "B.Fab" user "Ref Des/Assembly Bottom")
	)
	(footprint ""
		(layer "F.Cu")
		(at 322.7324 -35.052 -90)
		(property "Reference" "R6F2"
			(at 0 0 270)
			(layer "F.SilkS")
			(hide yes)
			(effects
				(font
					(size 1.27 1.27)
				)
			)
		)
		(property "Value" ""
			(at 0 0 270)
			(layer "F.Fab")
			(effects
				(font
					(size 1.27 1.27)
				)
			)
		)
		(duplicate_pad_numbers_are_jumpers no)
		(fp_poly
			(pts
				(xy -0.2794 -0.1016) (xy 0.2794 -0.1016) (xy 0.2794 0.9906) (xy -0.2794 0.9906)
			)
			(stroke
				(width 0)
				(type default)
			)
			(fill no)
			(layer "F.CrtYd")
		)
		(fp_line
			(start -0.2794 0.9906)
			(end 0.2794 0.9906)
			(stroke
				(width 0.1)
				(type default)
			)
			(layer "F.Fab")
		)
		(fp_line
			(start 0.2794 0.9906)
			(end 0.2794 -0.1016)
			(stroke
				(width 0.1)
				(type default)
			)
			(layer "F.Fab")
		)
		(fp_line
			(start -0.2794 -0.1016)
			(end -0.2794 0.9906)
			(stroke
				(width 0.1)
				(type default)
			)
			(layer "F.Fab")
		)
		(fp_line
			(start 0.2794 -0.1016)
			(end -0.2794 -0.1016)
			(stroke
				(width 0.1)
				(type default)
			)
			(layer "F.Fab")
		)
		(pad "1" smd rect
			(at 0 0 270)
			(size 0.508 0.508)
			(layers "F.Cu" "F.Mask" "F.Paste")
			(net "FM_ADR_COMPLETE_CPU1_N")
		)
		(pad "2" smd rect
			(at 0 0.889 270)
			(size 0.508 0.508)
			(layers "F.Cu" "F.Mask" "F.Paste")
			(net "FM_ADR_COMPLETE_KLM_N")
		)
		(zone
			(layer "F.Cu")
			(hatch none 0.5)
			(connect_pads
				(clearance 0)
			)
			(min_thickness 0.25)
			(keepout
				(tracks not_allowed)
				(vias allowed)
				(pads allowed)
				(copperpour not_allowed)
				(footprints allowed)
			)
			(placement
				(enabled no)
				(sheetname "")
			)
			(fill
				(thermal_gap 0.5)
				(thermal_bridge_width 0.5)
				(island_removal_mode 0)
			)
			(polygon
				(pts
					(xy 322.0974 -35.306) (xy 322.0974 -34.798) (xy 322.4784 -34.798) (xy 322.4784 -35.306)
				)
			)
		)
		(zone
			(layer "F.Cu")
			(hatch none 0.5)
			(connect_pads
				(clearance 0)
			)
			(min_thickness 0.25)
			(keepout
				(tracks allowed)
				(vias not_allowed)
				(pads allowed)
				(copperpour not_allowed)
				(footprints allowed)
			)
			(placement
				(enabled no)
				(sheetname "")
			)
			(fill
				(thermal_gap 0.5)
				(thermal_bridge_width 0.5)
				(island_removal_mode 0)
			)
			(polygon
				(pts
					(xy 322.4784 -35.306) (xy 322.4784 -34.798) (xy 322.0974 -34.798) (xy 322.0974 -35.306)
				)
			)
		)
	)
	(footprint ""
		(layer "F.Cu")
		(at 5.6388 -142.875 -90)
		(property "Reference" "RT7"
			(at 0 0 270)
			(layer "F.SilkS")
			(hide yes)
			(effects
				(font
					(size 1.27 1.27)
				)
			)
		)
		(property "Value" "*"
			(at -0.0254 -2.6289 270)
			(unlocked yes)
			(layer "F.Fab")
			(hide yes)
			(effects
				(font
					(size 1.27 1.016)
					(thickness 0.1524)
				)
			)
		)
		(property "Device Type" "1R3F-GP_RCL_GP-1R3F-GP,64.1R00A"
			(at -0.0254 -4.1529 270)
			(unlocked yes)
			(layer "F.Fab")
			(hide yes)
			(effects
				(font
					(size 1.27 1.016)
					(thickness 0.1524)
				)
			)
		)
		(duplicate_pad_numbers_are_jumpers no)
		(fp_line
			(start -0.4826 0)
			(end -0.2032 0)
			(stroke
				(width 0.2032)
				(type default)
			)
			(layer "F.SilkS")
		)
		(fp_line
			(start 0.2032 0)
			(end 0.4826 0)
			(stroke
				(width 0.2032)
				(type default)
			)
			(layer "F.SilkS")
		)
		(fp_rect
			(start -0.5842 1.3335)
			(end 0.5842 -1.3335)
			(stroke
				(width 0)
				(type default)
			)
			(fill no)
			(layer "F.CrtYd")
		)
		(fp_rect
			(start -0.5842 1.3335)
			(end 0.5842 -1.3335)
			(stroke
				(width 0)
				(type default)
			)
			(fill no)
			(layer "F.Fab")
		)
		(pad "1" smd custom
			(at 0 -0.762 270)
			(size 0.2159 0.2159)
			(layers "F.Cu" "F.Mask" "F.Paste")
			(net "VR_PVDDQ_KLM_PH2_RC")
			(options
				(clearance outline)
				(anchor circle)
			)
			(primitives
				(gr_poly
					(pts
						(arc
							(start -0.3302 -0.4318)
							(mid -0.402042 -0.402042)
							(end -0.4318 -0.3302)
						)
						(arc
							(start -0.4318 0.3302)
							(mid -0.402042 0.402042)
							(end -0.3302 0.4318)
						)
						(arc
							(start 0.3302 0.4318)
							(mid 0.402042 0.402042)
							(end 0.4318 0.3302)
						)
						(arc
							(start 0.4318 -0.3302)
							(mid 0.402042 -0.402042)
							(end 0.3302 -0.4318)
						)
					)
					(width 0)
					(fill yes)
				)
			)
		)
		(pad "2" smd custom
			(at 0 0.762 270)
			(size 0.2159 0.2159)
			(layers "F.Cu" "F.Mask" "F.Paste")
			(net "GND")
			(options
				(clearance outline)
				(anchor circle)
			)
			(primitives
				(gr_poly
					(pts
						(arc
							(start -0.3302 -0.4318)
							(mid -0.402042 -0.402042)
							(end -0.4318 -0.3302)
						)
						(arc
							(start -0.4318 0.3302)
							(mid -0.402042 0.402042)
							(end -0.3302 0.4318)
						)
						(arc
							(start 0.3302 0.4318)
							(mid 0.402042 0.402042)
							(end 0.4318 0.3302)
						)
						(arc
							(start 0.4318 -0.3302)
							(mid 0.402042 -0.402042)
							(end 0.3302 -0.4318)
						)
					)
					(width 0)
					(fill yes)
				)
			)
		)
	)
	(footprint ""
		(layer "F.Cu")
		(at 16.764 -69.977 -90)
		(property "Reference" "R1D45"
			(at 0 0 270)
			(layer "F.SilkS")
			(hide yes)
			(effects
				(font
					(size 1.27 1.27)
				)
			)
		)
		(property "Value" ""
			(at 0 0 270)
			(layer "F.Fab")
			(effects
				(font
					(size 1.27 1.27)
				)
			)
		)
		(duplicate_pad_numbers_are_jumpers no)
		(fp_rect
			(start -0.2794 0.9906)
			(end 0.2794 -0.1016)
			(stroke
				(width 0)
				(type default)
			)
			(fill no)
			(layer "F.CrtYd")
		)
		(fp_line
			(start -0.2794 0.9906)
			(end 0.2794 0.9906)
			(stroke
				(width 0.1)
				(type default)
			)
			(layer "F.Fab")
		)
		(fp_line
			(start 0.2794 0.9906)
			(end 0.2794 -0.1016)
			(stroke
				(width 0.1)
				(type default)
			)
			(layer "F.Fab")
		)
		(fp_line
			(start -0.2794 -0.1016)
			(end -0.2794 0.9906)
			(stroke
				(width 0.1)
				(type default)
			)
			(layer "F.Fab")
		)
		(fp_line
			(start 0.2794 -0.1016)
			(end -0.2794 -0.1016)
			(stroke
				(width 0.1)
				(type default)
			)
			(layer "F.Fab")
		)
		(pad "1" smd rect
			(at 0 0 270)
			(size 0.508 0.508)
			(layers "F.Cu" "F.Mask" "F.Paste")
			(net "A_HSC_MON")
		)
		(pad "2" smd rect
			(at 0 0.889 270)
			(size 0.508 0.508)
			(layers "F.Cu" "F.Mask" "F.Paste")
			(net "A_HSC_HSN")
		)
		(zone
			(layer "F.Cu")
			(hatch none 0.5)
			(connect_pads
				(clearance 0)
			)
			(min_thickness 0.25)
			(keepout
				(tracks not_allowed)
				(vias allowed)
				(pads allowed)
				(copperpour not_allowed)
				(footprints allowed)
			)
			(placement
				(enabled no)
				(sheetname "")
			)
			(fill
				(thermal_gap 0.5)
				(thermal_bridge_width 0.5)
				(island_removal_mode 0)
			)
			(polygon
				(pts
					(xy 16.129 -70.231) (xy 16.129 -69.723) (xy 16.51 -69.723) (xy 16.51 -70.231)
				)
			)
		)
		(zone
			(layer "F.Cu")
			(hatch none 0.5)
			(connect_pads
				(clearance 0)
			)
			(min_thickness 0.25)
			(keepout
				(tracks allowed)
				(vias not_allowed)
				(pads allowed)
				(copperpour not_allowed)
				(footprints allowed)
			)
			(placement
				(enabled no)
				(sheetname "")
			)
			(fill
				(thermal_gap 0.5)
				(thermal_bridge_width 0.5)
				(island_removal_mode 0)
			)
			(polygon
				(pts
					(xy 16.129 -70.231) (xy 16.129 -69.723) (xy 16.51 -69.723) (xy 16.51 -70.231)
				)
			)
		)
	)
)
